# T6G (Grand Teton) — schematic netlist excerpt (pin names and nets, part order shuffled) for the footprints in the layout excerpt that follows; sources: Cadence DE-HDL packaged netlist, KiCad conversion of 04192023_DAF0TMB3IC0_F0TG_MB_C_brd_V02_OCP.brd

PC348_3  Q_CAP  0.1UF 25V 10% X7R  pkg 0402  page 216 : A = SW_P12V_AUX_PVDDCR_SOC_P1_FLT ; B = GND
C20  Q_CAP  0.1UF 16V 10% X7R  pkg C0402  page 85 : A = P3V3_AUX ; B = GND
PC6012  Q_CAP  22UF 16V 20% X6S  pkg C0805  page 269 : A = SW_P12V_AUX_P1V8_AUX_FLT ; B = GND

(kicad_pcb
	(version 20260206)
	(generator "pcbnew")
	(generator_version "10.0")
	(general
		(thickness 1.6)
		(legacy_teardrops no)
	)
	(paper "A4")
	(title_block
		(title "04192023_DAF0TMB3IC0_F0TG_MB_C_brd_V02_OCP.brd")
		(comment 1 "Grand Teton / footprints 1392-1394 of 8354")
	)
	(layers
		(0 "F.Cu" signal "TOP")
		(4 "In1.Cu" signal "GND")
		(6 "In2.Cu" signal "IN1")
		(8 "In3.Cu" signal "GND1")
		(10 "In4.Cu" signal "IN2")
		(12 "In5.Cu" signal "GND2")
		(14 "In6.Cu" signal "IN3")
		(16 "In7.Cu" signal "GND3")
		(18 "In8.Cu" signal "VCC")
		(20 "In9.Cu" signal "VCC1")
		(22 "In10.Cu" signal "GND4")
		(24 "In11.Cu" signal "IN4")
		(26 "In12.Cu" signal "GND5")
		(28 "In13.Cu" signal "IN5")
		(30 "In14.Cu" signal "GND6")
		(32 "In15.Cu" signal "IN6")
		(34 "In16.Cu" signal "GND7")
		(2 "B.Cu" signal "BOTTOM")
		(9 "F.Adhes" user "F.Adhesive")
		(11 "B.Adhes" user "B.Adhesive")
		(13 "F.Paste" user "Package Geometry/Pastemask Top")
		(15 "B.Paste" user "Package Geometry/Pastemask Bottom")
		(5 "F.SilkS" user "Ref Des/Silkscreen Top")
		(7 "B.SilkS" user "Ref Des/Silkscreen Bottom")
		(1 "F.Mask" user "Board Geometry/Soldermask Top")
		(3 "B.Mask" user "Board Geometry/Soldermask Bottom")
		(17 "Dwgs.User" user "User.Drawings")
		(19 "Cmts.User" user "User.Comments")
		(21 "Eco1.User" user "User.Eco1")
		(23 "Eco2.User" user "User.Eco2")
		(25 "Edge.Cuts" user "Board Geometry/Outline")
		(27 "Margin" user)
		(31 "F.CrtYd" user "Package Geometry/Place Bound Top")
		(29 "B.CrtYd" user "Package Geometry/Place Bound Bottom")
		(35 "F.Fab" user "Ref Des/Assembly Top")
		(33 "B.Fab" user "Ref Des/Assembly Bottom")
	)
	(footprint ""
		(layer "F.Cu")
		(at 127.761492 -156.441902 90)
		(property "Reference" "PC348_3"
			(at 0 0 90)
			(layer "F.SilkS")
			(hide yes)
			(effects
				(font
					(size 1.27 1.27)
				)
			)
		)
		(property "Value" ""
			(at 0 0 90)
			(layer "F.Fab")
			(effects
				(font
					(size 1.27 1.27)
				)
			)
		)
		(duplicate_pad_numbers_are_jumpers no)
		(fp_line
			(start 0.7874 -0.4064)
			(end 0.7874 0.4064)
			(stroke
				(width 0.1524)
				(type default)
			)
			(layer "F.SilkS")
		)
		(fp_line
			(start -0.7874 -0.4064)
			(end 0.7874 -0.4064)
			(stroke
				(width 0.1524)
				(type default)
			)
			(layer "F.SilkS")
		)
		(fp_line
			(start 0.7874 0.4064)
			(end -0.7874 0.4064)
			(stroke
				(width 0.1524)
				(type default)
			)
			(layer "F.SilkS")
		)
		(fp_line
			(start -0.7874 0.4064)
			(end -0.7874 -0.4064)
			(stroke
				(width 0.1524)
				(type default)
			)
			(layer "F.SilkS")
		)
		(fp_line
			(start -0.12065 -0.305054)
			(end -0.12065 -0.2794)
			(stroke
				(width 0.1)
				(type default)
			)
			(layer "F.Fab")
		)
		(fp_line
			(start -0.67945 -0.305054)
			(end -0.12065 -0.305054)
			(stroke
				(width 0.1)
				(type default)
			)
			(layer "F.Fab")
		)
		(fp_line
			(start 0.67945 -0.3048)
			(end 0.67945 0.3048)
			(stroke
				(width 0.1)
				(type default)
			)
			(layer "F.Fab")
		)
		(fp_line
			(start 0.12065 -0.3048)
			(end 0.67945 -0.3048)
			(stroke
				(width 0.1)
				(type default)
			)
			(layer "F.Fab")
		)
		(fp_line
			(start 0.12065 -0.2794)
			(end 0.12065 -0.3048)
			(stroke
				(width 0.1)
				(type default)
			)
			(layer "F.Fab")
		)
		(fp_line
			(start -0.12065 -0.2794)
			(end 0.12065 -0.2794)
			(stroke
				(width 0.1)
				(type default)
			)
			(layer "F.Fab")
		)
		(fp_line
			(start 0.120396 0.2794)
			(end -0.12065 0.2794)
			(stroke
				(width 0.1)
				(type default)
			)
			(layer "F.Fab")
		)
		(fp_line
			(start -0.12065 0.2794)
			(end -0.12065 0.3048)
			(stroke
				(width 0.1)
				(type default)
			)
			(layer "F.Fab")
		)
		(fp_line
			(start 0.67945 0.3048)
			(end 0.120396 0.3048)
			(stroke
				(width 0.1)
				(type default)
			)
			(layer "F.Fab")
		)
		(fp_line
			(start 0.120396 0.3048)
			(end 0.120396 0.2794)
			(stroke
				(width 0.1)
				(type default)
			)
			(layer "F.Fab")
		)
		(fp_line
			(start -0.12065 0.3048)
			(end -0.67945 0.3048)
			(stroke
				(width 0.1)
				(type default)
			)
			(layer "F.Fab")
		)
		(fp_line
			(start -0.67945 0.3048)
			(end -0.67945 -0.305054)
			(stroke
				(width 0.1)
				(type default)
			)
			(layer "F.Fab")
		)
		(pad "1" smd circle
			(at -0.40005 0 90)
			(size 0 0)
			(layers "F.Cu" "F.Mask" "F.Paste")
			(net "SW_P12V_AUX_PVDDCR_SOC_P1_FLT")
		)
		(pad "2" smd circle
			(at 0.40005 0 90)
			(size 0 0)
			(layers "F.Cu" "F.Mask" "F.Paste")
			(net "GND")
		)
	)
	(footprint ""
		(layer "F.Cu")
		(at 138.143234 -79.288894 90)
		(property "Reference" "PC6012"
			(at 0 0 90)
			(layer "F.SilkS")
			(hide yes)
			(effects
				(font
					(size 1.27 1.27)
				)
			)
		)
		(property "Value" ""
			(at 0 0 90)
			(layer "F.Fab")
			(effects
				(font
					(size 1.27 1.27)
				)
			)
		)
		(duplicate_pad_numbers_are_jumpers no)
		(fp_line
			(start 1.524 -0.762)
			(end 1.524 0.762)
			(stroke
				(width 0.1524)
				(type default)
			)
			(layer "F.SilkS")
		)
		(fp_line
			(start -1.524 -0.762)
			(end 1.524 -0.762)
			(stroke
				(width 0.1524)
				(type default)
			)
			(layer "F.SilkS")
		)
		(fp_line
			(start 1.524 0.762)
			(end -1.524 0.762)
			(stroke
				(width 0.1524)
				(type default)
			)
			(layer "F.SilkS")
		)
		(fp_line
			(start -1.524 0.762)
			(end -1.524 -0.762)
			(stroke
				(width 0.1524)
				(type default)
			)
			(layer "F.SilkS")
		)
		(fp_line
			(start 1.1049 -0.724916)
			(end -1.1049 -0.724916)
			(stroke
				(width 0.1)
				(type default)
			)
			(layer "F.Fab")
		)
		(fp_line
			(start -1.1049 -0.724916)
			(end -1.1049 0.724916)
			(stroke
				(width 0.1)
				(type default)
			)
			(layer "F.Fab")
		)
		(fp_line
			(start 1.1049 0.724916)
			(end 1.1049 -0.724916)
			(stroke
				(width 0.1)
				(type default)
			)
			(layer "F.Fab")
		)
		(fp_line
			(start -1.1049 0.724916)
			(end 1.1049 0.724916)
			(stroke
				(width 0.1)
				(type default)
			)
			(layer "F.Fab")
		)
		(pad "1" smd rect
			(at -0.889 0 270)
			(size 1.016 1.27)
			(layers "F.Cu" "F.Mask" "F.Paste")
			(net "SW_P12V_AUX_P1V8_AUX_FLT")
		)
		(pad "2" smd rect
			(at 0.889 0 270)
			(size 1.016 1.27)
			(layers "F.Cu" "F.Mask" "F.Paste")
			(net "GND")
		)
	)
	(footprint ""
		(layer "F.Cu")
		(at 154.277822 -66.04254 180)
		(property "Reference" "C20"
			(at 0 0 180)
			(layer "F.SilkS")
			(hide yes)
			(effects
				(font
					(size 1.27 1.27)
				)
			)
		)
		(property "Value" ""
			(at 0 0 180)
			(layer "F.Fab")
			(effects
				(font
					(size 1.27 1.27)
				)
			)
		)
		(duplicate_pad_numbers_are_jumpers no)
		(fp_line
			(start 0.7874 0.4064)
			(end -0.7874 0.4064)
			(stroke
				(width 0.1524)
				(type default)
			)
			(layer "F.SilkS")
		)
		(fp_line
			(start 0.7874 -0.4064)
			(end 0.7874 0.4064)
			(stroke
				(width 0.1524)
				(type default)
			)
			(layer "F.SilkS")
		)
		(fp_line
			(start -0.7874 0.4064)
			(end -0.7874 -0.4064)
			(stroke
				(width 0.1524)
				(type default)
			)
			(layer "F.SilkS")
		)
		(fp_line
			(start -0.7874 -0.4064)
			(end 0.7874 -0.4064)
			(stroke
				(width 0.1524)
				(type default)
			)
			(layer "F.SilkS")
		)
		(fp_line
			(start 0.67945 0.3048)
			(end 0.120396 0.3048)
			(stroke
				(width 0.1)
				(type default)
			)
			(layer "F.Fab")
		)
		(fp_line
			(start 0.67945 -0.3048)
			(end 0.67945 0.3048)
			(stroke
				(width 0.1)
				(type default)
			)
			(layer "F.Fab")
		)
		(fp_line
			(start 0.12065 -0.2794)
			(end 0.12065 -0.3048)
			(stroke
				(width 0.1)
				(type default)
			)
			(layer "F.Fab")
		)
		(fp_line
			(start 0.12065 -0.3048)
			(end 0.67945 -0.3048)
			(stroke
				(width 0.1)
				(type default)
			)
			(layer "F.Fab")
		)
		(fp_line
			(start 0.120396 0.3048)
			(end 0.120396 0.2794)
			(stroke
				(width 0.1)
				(type default)
			)
			(layer "F.Fab")
		)
		(fp_line
			(start 0.120396 0.2794)
			(end -0.12065 0.2794)
			(stroke
				(width 0.1)
				(type default)
			)
			(layer "F.Fab")
		)
		(fp_line
			(start -0.12065 0.3048)
			(end -0.67945 0.3048)
			(stroke
				(width 0.1)
				(type default)
			)
			(layer "F.Fab")
		)
		(fp_line
			(start -0.12065 0.2794)
			(end -0.12065 0.3048)
			(stroke
				(width 0.1)
				(type default)
			)
			(layer "F.Fab")
		)
		(fp_line
			(start -0.12065 -0.2794)
			(end 0.12065 -0.2794)
			(stroke
				(width 0.1)
				(type default)
			)
			(layer "F.Fab")
		)
		(fp_line
			(start -0.12065 -0.305054)
			(end -0.12065 -0.2794)
			(stroke
				(width 0.1)
				(type default)
			)
			(layer "F.Fab")
		)
		(fp_line
			(start -0.67945 0.3048)
			(end -0.67945 -0.305054)
			(stroke
				(width 0.1)
				(type default)
			)
			(layer "F.Fab")
		)
		(fp_line
			(start -0.67945 -0.305054)
			(end -0.12065 -0.305054)
			(stroke
				(width 0.1)
				(type default)
			)
			(layer "F.Fab")
		)
		(pad "1" smd circle
			(at -0.40005 0 180)
			(size 0 0)
			(layers "F.Cu" "F.Mask" "F.Paste")
			(net "P3V3_AUX")
		)
		(pad "2" smd circle
			(at 0.40005 0 180)
			(size 0 0)
			(layers "F.Cu" "F.Mask" "F.Paste")
			(net "GND")
		)
	)
)
